(kicad_pcb
	(version 20260206)
	(generator "pcbnew")
	(generator_version "10.0")
	(general
		(thickness 1.6)
		(legacy_teardrops no)
	)
	(paper "A4")
	(title_block
		(title "04192023_DAF0TMB3IC0_F0TG_MB_C_brd_V02_OCP.brd")
		(comment 1 "Grand Teton / footprints 2713-2717 of 8354")
	)
	(layers
		(0 "F.Cu" signal "TOP")
		(4 "In1.Cu" signal "GND")
		(6 "In2.Cu" signal "IN1")
		(8 "In3.Cu" signal "GND1")
		(10 "In4.Cu" signal "IN2")
		(12 "In5.Cu" signal "GND2")
		(14 "In6.Cu" signal "IN3")
		(16 "In7.Cu" signal "GND3")
		(18 "In8.Cu" signal "VCC")
		(20 "In9.Cu" signal "VCC1")
		(22 "In10.Cu" signal "GND4")
		(24 "In11.Cu" signal "IN4")
		(26 "In12.Cu" signal "GND5")
		(28 "In13.Cu" signal "IN5")
		(30 "In14.Cu" signal "GND6")
		(32 "In15.Cu" signal "IN6")
		(34 "In16.Cu" signal "GND7")
		(2 "B.Cu" signal "BOTTOM")
		(9 "F.Adhes" user "F.Adhesive")
		(11 "B.Adhes" user "B.Adhesive")
		(13 "F.Paste" user "Package Geometry/Pastemask Top")
		(15 "B.Paste" user "Package Geometry/Pastemask Bottom")
		(5 "F.SilkS" user "Ref Des/Silkscreen Top")
		(7 "B.SilkS" user "Ref Des/Silkscreen Bottom")
		(1 "F.Mask" user "Board Geometry/Soldermask Top")
		(3 "B.Mask" user "Board Geometry/Soldermask Bottom")
		(17 "Dwgs.User" user "User.Drawings")
		(19 "Cmts.User" user "User.Comments")
		(21 "Eco1.User" user "User.Eco1")
		(23 "Eco2.User" user "User.Eco2")
		(25 "Edge.Cuts" user "Board Geometry/Outline")
		(27 "Margin" user)
		(31 "F.CrtYd" user "Package Geometry/Place Bound Top")
		(29 "B.CrtYd" user "Package Geometry/Place Bound Bottom")
		(35 "F.Fab" user "Ref Des/Assembly Top")
		(33 "B.Fab" user "Ref Des/Assembly Bottom")
	)
	(footprint ""
		(layer "F.Cu")
		(at 21.938996 -390.949434 90)
		(property "Reference" "PC6645"
			(at 0 0 90)
			(layer "F.SilkS")
			(hide yes)
			(effects
				(font
					(size 1.27 1.27)
				)
			)
		)
		(property "Value" ""
			(at 0 0 90)
			(layer "F.Fab")
			(effects
				(font
					(size 1.27 1.27)
				)
			)
		)
		(duplicate_pad_numbers_are_jumpers no)
		(fp_line
			(start 0.7874 -0.4064)
			(end 0.7874 -0.221996)
			(stroke
				(width 0.1524)
				(type default)
			)
			(layer "F.SilkS")
		)
		(fp_line
			(start -0.7874 -0.4064)
			(end 0.7874 -0.4064)
			(stroke
				(width 0.1524)
				(type default)
			)
			(layer "F.SilkS")
		)
		(fp_line
			(start 0.464566 0.4064)
			(end -0.7874 0.4064)
			(stroke
				(width 0.1524)
				(type default)
			)
			(layer "F.SilkS")
		)
		(fp_line
			(start -0.7874 0.4064)
			(end -0.7874 -0.4064)
			(stroke
				(width 0.1524)
				(type default)
			)
			(layer "F.SilkS")
		)
		(fp_line
			(start -0.12065 -0.305054)
			(end -0.12065 -0.2794)
			(stroke
				(width 0.1)
				(type default)
			)
			(layer "F.Fab")
		)
		(fp_line
			(start -0.67945 -0.305054)
			(end -0.12065 -0.305054)
			(stroke
				(width 0.1)
				(type default)
			)
			(layer "F.Fab")
		)
		(fp_line
			(start 0.67945 -0.3048)
			(end 0.67945 0.3048)
			(stroke
				(width 0.1)
				(type default)
			)
			(layer "F.Fab")
		)
		(fp_line
			(start 0.12065 -0.3048)
			(end 0.67945 -0.3048)
			(stroke
				(width 0.1)
				(type default)
			)
			(layer "F.Fab")
		)
		(fp_line
			(start 0.12065 -0.2794)
			(end 0.12065 -0.3048)
			(stroke
				(width 0.1)
				(type default)
			)
			(layer "F.Fab")
		)
		(fp_line
			(start -0.12065 -0.2794)
			(end 0.12065 -0.2794)
			(stroke
				(width 0.1)
				(type default)
			)
			(layer "F.Fab")
		)
		(fp_line
			(start 0.120396 0.2794)
			(end -0.12065 0.2794)
			(stroke
				(width 0.1)
				(type default)
			)
			(layer "F.Fab")
		)
		(fp_line
			(start -0.12065 0.2794)
			(end -0.12065 0.3048)
			(stroke
				(width 0.1)
				(type default)
			)
			(layer "F.Fab")
		)
		(fp_line
			(start 0.67945 0.3048)
			(end 0.120396 0.3048)
			(stroke
				(width 0.1)
				(type default)
			)
			(layer "F.Fab")
		)
		(fp_line
			(start 0.120396 0.3048)
			(end 0.120396 0.2794)
			(stroke
				(width 0.1)
				(type default)
			)
			(layer "F.Fab")
		)
		(fp_line
			(start -0.12065 0.3048)
			(end -0.67945 0.3048)
			(stroke
				(width 0.1)
				(type default)
			)
			(layer "F.Fab")
		)
		(fp_line
			(start -0.67945 0.3048)
			(end -0.67945 -0.305054)
			(stroke
				(width 0.1)
				(type default)
			)
			(layer "F.Fab")
		)
		(pad "1" smd circle
			(at -0.40005 0 90)
			(size 0 0)
			(layers "F.Cu" "F.Mask" "F.Paste")
			(net "P0V9_RETIMER_CPU1_VCC2")
		)
		(pad "2" smd circle
			(at 0.40005 0 90)
			(size 0 0)
			(layers "F.Cu" "F.Mask" "F.Paste")
			(net "GND")
		)
	)
	(footprint ""
		(layer "F.Cu")
		(at 228.650038 -44.494958)
		(property "Reference" "H77"
			(at -1.143 -3.266948 0)
			(unlocked yes)
			(layer "B.SilkS")
			(effects
				(font
					(size 0.7874 0.5842)
					(thickness 0.1524)
				)
				(justify left mirror)
			)
		)
		(property "Value" ""
			(at 0 0 0)
			(layer "F.Fab")
			(effects
				(font
					(size 1.27 1.27)
				)
			)
		)
		(duplicate_pad_numbers_are_jumpers no)
		(pad "1" thru_hole rect
			(at 0 0)
			(size 4.2164 5.0038)
			(drill 2.0066
				(offset 0.099822 0)
			)
			(layers "*.Cu" "*.Mask")
			(remove_unused_layers no)
			(net "GND")
			(clearance -0.8509)
			(padstack
				(mode front_inner_back)
				(layer "Inner"
					(shape circle)
					(size 4.0132 4.0132)
					(clearance -0.7493)
				)
				(layer "B.Cu"
					(shape circle)
					(size 4.0132 4.0132)
					(clearance -0.7493)
				)
			)
		)
	)
	(footprint ""
		(layer "F.Cu")
		(at 132.42417 -156.531056 180)
		(property "Reference" "PU32"
			(at 6.086856 -5.12572 0)
			(unlocked yes)
			(layer "F.SilkS")
			(effects
				(font
					(size 0.7874 0.5842)
					(thickness 0.1524)
				)
				(justify left)
			)
		)
		(property "Value" ""
			(at 0 0 180)
			(layer "F.Fab")
			(effects
				(font
					(size 1.27 1.27)
				)
			)
		)
		(duplicate_pad_numbers_are_jumpers no)
		(fp_line
			(start 2.500122 2.999994)
			(end 2.2987 2.999994)
			(stroke
				(width 0.1524)
				(type default)
			)
			(layer "F.SilkS")
		)
		(fp_line
			(start 2.500122 2.339594)
			(end 2.500122 2.999994)
			(stroke
				(width 0.1524)
				(type default)
			)
			(layer "F.SilkS")
		)
		(fp_line
			(start 2.500122 -2.999994)
			(end 2.500122 -2.44348)
			(stroke
				(width 0.1524)
				(type default)
			)
			(layer "F.SilkS")
		)
		(fp_line
			(start 2.31394 -2.999994)
			(end 2.500122 -2.999994)
			(stroke
				(width 0.1524)
				(type default)
			)
			(layer "F.SilkS")
		)
		(fp_line
			(start -2.2987 2.999994)
			(end -2.500122 2.999994)
			(stroke
				(width 0.1524)
				(type default)
			)
			(layer "F.SilkS")
		)
		(fp_line
			(start -2.500122 2.999994)
			(end -2.500122 2.339594)
			(stroke
				(width 0.1524)
				(type default)
			)
			(layer "F.SilkS")
		)
		(fp_line
			(start -2.500122 0.6604)
			(end -2.500122 0.229108)
			(stroke
				(width 0.1524)
				(type default)
			)
			(layer "F.SilkS")
		)
		(fp_line
			(start -2.500122 -2.529078)
			(end -2.500122 -2.999994)
			(stroke
				(width 0.1524)
				(type default)
			)
			(layer "F.SilkS")
		)
		(fp_line
			(start -2.500122 -2.999994)
			(end -2.24409 -2.999994)
			(stroke
				(width 0.1524)
				(type default)
			)
			(layer "F.SilkS")
		)
		(fp_poly
			(pts
				(xy -2.710688 -2.451608) (xy -3.384296 -2.676144) (xy -2.935224 -3.125216)
			)
			(stroke
				(width 0)
				(type default)
			)
			(fill yes)
			(layer "F.SilkS")
		)
		(fp_line
			(start 2.500122 2.999994)
			(end -2.500122 2.999994)
			(stroke
				(width 0.1)
				(type default)
			)
			(layer "F.Fab")
		)
		(fp_line
			(start 2.500122 -2.999994)
			(end 2.500122 2.999994)
			(stroke
				(width 0.1)
				(type default)
			)
			(layer "F.Fab")
		)
		(fp_line
			(start -2.500122 2.999994)
			(end -2.500122 -2.999994)
			(stroke
				(width 0.1)
				(type default)
			)
			(layer "F.Fab")
		)
		(fp_line
			(start -2.500122 -2.999994)
			(end 2.500122 -2.999994)
			(stroke
				(width 0.1)
				(type default)
			)
			(layer "F.Fab")
		)
		(fp_poly
			(pts
				(xy -4.218432 -2.783078) (xy -4.218432 -1.767078) (xy -3.202432 -2.275078)
			)
			(stroke
				(width 0)
				(type default)
			)
			(fill yes)
			(layer "F.Fab")
		)
		(pad "1" smd rect
			(at -2.400046 -2.275078 270)
			(size 0.2286 0.6096)
			(layers "F.Cu" "F.Mask" "F.Paste")
			(net "PVDDCR_SOC_P1_VOS3")
		)
		(pad "2" smd rect
			(at -2.400046 -1.82499 270)
			(size 0.2286 0.6096)
			(layers "F.Cu" "F.Mask" "F.Paste")
			(net "GND")
		)
		(pad "3" smd rect
			(at -2.400046 -1.374902 270)
			(size 0.2286 0.6096)
			(layers "F.Cu" "F.Mask" "F.Paste")
			(net "PVDDCR_SOC_P1_VCC3")
		)
		(pad "4" smd rect
			(at -2.400046 -0.925068 270)
			(size 0.2286 0.6096)
			(layers "F.Cu" "F.Mask" "F.Paste")
			(net "PVDDCR_CPU0_P1_PVCC")
		)
		(pad "5" smd rect
			(at -2.400046 -0.47498 270)
			(size 0.2286 0.6096)
			(layers "F.Cu" "F.Mask" "F.Paste")
			(net "GND")
		)
		(pad "6" smd rect
			(at -2.400046 -0.024892 270)
			(size 0.2286 0.6096)
			(layers "F.Cu" "F.Mask" "F.Paste")
			(net "NC_PVDDCR_SOC_P1_GL1_3")
		)
		(pad "7_9-20_24" smd circle
			(at 0 1.150112 270)
			(size 0 0)
			(layers "F.Cu" "F.Mask" "F.Paste")
			(net "GND")
		)
		(pad "10_19" smd rect
			(at 0 2.899918 270)
			(size 0.6096 4.318)
			(layers "F.Cu" "F.Mask" "F.Paste")
			(net "SW_PVDDCR_SOC_P1_SW3")
		)
		(pad "25_29" smd rect
			(at 1.549908 -1.279906 90)
			(size 2.0574 2.3114)
			(layers "F.Cu" "F.Mask" "F.Paste")
			(net "SW_P12V_AUX_PVDDCR_SOC_P1_FLT")
		)
		(pad "30" smd rect
			(at 2.05994 -2.899918 180)
			(size 0.2286 0.6096)
			(layers "F.Cu" "F.Mask" "F.Paste")
			(net "SW_P12V_AUX_PVDDCR_SOC_P1_FLT")
		)
		(pad "31" smd rect
			(at 1.610106 -2.899918 180)
			(size 0.2286 0.6096)
			(layers "F.Cu" "F.Mask" "F.Paste")
			(net "NC_PVDDCR_SOC_P1_DNC3")
		)
		(pad "32" smd rect
			(at 1.160018 -2.899918 180)
			(size 0.2286 0.6096)
			(layers "F.Cu" "F.Mask" "F.Paste")
			(net "SW_PVDDCR_SOC_P1_PH3")
		)
		(pad "33" smd rect
			(at 0.70993 -2.899918 180)
			(size 0.2286 0.6096)
			(layers "F.Cu" "F.Mask" "F.Paste")
			(net "SW_PVDDCR_SOC_P1_BOOT3")
		)
		(pad "34" smd rect
			(at 0.260096 -2.899918 180)
			(size 0.2286 0.6096)
			(layers "F.Cu" "F.Mask" "F.Paste")
			(net "PVDDCR_SOC_P1_PWM3")
		)
		(pad "35" smd rect
			(at -0.189992 -2.899918 180)
			(size 0.2286 0.6096)
			(layers "F.Cu" "F.Mask" "F.Paste")
			(net "PVDDCR_SOC_P1_VCC3")
		)
		(pad "36" smd rect
			(at -0.64008 -2.899918 180)
			(size 0.2286 0.6096)
			(layers "F.Cu" "F.Mask" "F.Paste")
			(net "PVDDCR_SOC_P1_TEMP1")
		)
		(pad "37" smd rect
			(at -1.089914 -2.899918 180)
			(size 0.2286 0.6096)
			(layers "F.Cu" "F.Mask" "F.Paste")
			(net "PVDDCR_SOC_P1_LSET3")
		)
		(pad "38" smd rect
			(at -1.540002 -2.899918 180)
			(size 0.2286 0.6096)
			(layers "F.Cu" "F.Mask" "F.Paste")
			(net "PVDDCR_SOC_P1_IMON3")
		)
		(pad "39" smd rect
			(at -1.99009 -2.899918 180)
			(size 0.2286 0.6096)
			(layers "F.Cu" "F.Mask" "F.Paste")
			(net "PVDDCR_CPU0_P1_VCCS")
		)
		(pad "40" smd rect
			(at -0.87503 -1.27508 180)
			(size 1.7526 1.9558)
			(layers "F.Cu" "F.Mask" "F.Paste")
			(net "GND")
		)
		(pad "41" smd rect
			(at -1.525016 0.249936 90)
			(size 0.3048 0.4572)
			(layers "F.Cu" "F.Mask" "F.Paste")
			(net "NC_PVDDCR_SOC_P1_GL2_3")
		)
		(zone
			(layer "F.Cu")
			(hatch none 0.5)
			(connect_pads
				(clearance 0)
			)
			(min_thickness 0.25)
			(keepout
				(tracks not_allowed)
				(vias allowed)
				(pads allowed)
				(copperpour not_allowed)
				(footprints allowed)
			)
			(placement
				(enabled no)
				(sheetname "")
			)
			(fill
				(thermal_gap 0.5)
				(thermal_bridge_width 0.5)
				(island_removal_mode 0)
			)
			(polygon
				(pts
					(xy 134.924292 -159.075374) (xy 134.924292 -158.78175) (xy 129.924048 -158.78175) (xy 129.924048 -159.075374)
					(xy 130.21437 -159.075374) (xy 134.63397 -159.075374)
				)
			)
		)
		(zone
			(layer "F.Cu")
			(hatch none 0.5)
			(connect_pads
				(clearance 0)
			)
			(min_thickness 0.25)
			(keepout
				(tracks not_allowed)
				(vias allowed)
				(pads allowed)
				(copperpour not_allowed)
				(footprints allowed)
			)
			(placement
				(enabled no)
				(sheetname "")
			)
			(fill
				(thermal_gap 0.5)
				(thermal_bridge_width 0.5)
				(island_removal_mode 0)
			)
			(polygon
				(pts
					(xy 132.3721 -156.284676) (xy 132.3721 -154.227276) (xy 134.2263 -154.227276) (xy 134.2263 -154.468322)
					(xy 134.468616 -154.468322) (xy 134.468616 -153.986738) (xy 130.558794 -153.986738) (xy 130.558794 -154.17165)
					(xy 132.080762 -154.17165) (xy 132.080762 -156.33065) (xy 129.924048 -156.33065) (xy 129.924048 -156.580332)
					(xy 132.076444 -156.580332)
				)
			)
		)
	)
	(footprint ""
		(layer "F.Cu")
		(at 65.572894 -35.784028)
		(property "Reference" "R4059"
			(at 0 0 0)
			(layer "F.SilkS")
			(hide yes)
			(effects
				(font
					(size 1.27 1.27)
				)
			)
		)
		(property "Value" ""
			(at 0 0 0)
			(layer "F.Fab")
			(effects
				(font
					(size 1.27 1.27)
				)
			)
		)
		(duplicate_pad_numbers_are_jumpers no)
		(fp_line
			(start -0.7874 -0.4064)
			(end 0.7874 -0.4064)
			(stroke
				(width 0.1524)
				(type default)
			)
			(layer "F.SilkS")
		)
		(fp_line
			(start -0.7874 0.4064)
			(end -0.7874 -0.4064)
			(stroke
				(width 0.1524)
				(type default)
			)
			(layer "F.SilkS")
		)
		(fp_line
			(start 0.7874 -0.4064)
			(end 0.7874 0.4064)
			(stroke
				(width 0.1524)
				(type default)
			)
			(layer "F.SilkS")
		)
		(fp_line
			(start 0.7874 0.4064)
			(end -0.7874 0.4064)
			(stroke
				(width 0.1524)
				(type default)
			)
			(layer "F.SilkS")
		)
		(fp_line
			(start -0.67945 -0.305054)
			(end -0.12065 -0.305054)
			(stroke
				(width 0.1)
				(type default)
			)
			(layer "F.Fab")
		)
		(fp_line
			(start -0.67945 0.3048)
			(end -0.67945 -0.305054)
			(stroke
				(width 0.1)
				(type default)
			)
			(layer "F.Fab")
		)
		(fp_line
			(start -0.12065 -0.305054)
			(end -0.12065 -0.2794)
			(stroke
				(width 0.1)
				(type default)
			)
			(layer "F.Fab")
		)
		(fp_line
			(start -0.12065 -0.2794)
			(end 0.12065 -0.2794)
			(stroke
				(width 0.1)
				(type default)
			)
			(layer "F.Fab")
		)
		(fp_line
			(start -0.12065 0.2794)
			(end -0.12065 0.3048)
			(stroke
				(width 0.1)
				(type default)
			)
			(layer "F.Fab")
		)
		(fp_line
			(start -0.12065 0.3048)
			(end -0.67945 0.3048)
			(stroke
				(width 0.1)
				(type default)
			)
			(layer "F.Fab")
		)
		(fp_line
			(start 0.120396 0.2794)
			(end -0.12065 0.2794)
			(stroke
				(width 0.1)
				(type default)
			)
			(layer "F.Fab")
		)
		(fp_line
			(start 0.120396 0.3048)
			(end 0.120396 0.2794)
			(stroke
				(width 0.1)
				(type default)
			)
			(layer "F.Fab")
		)
		(fp_line
			(start 0.12065 -0.3048)
			(end 0.67945 -0.3048)
			(stroke
				(width 0.1)
				(type default)
			)
			(layer "F.Fab")
		)
		(fp_line
			(start 0.12065 -0.2794)
			(end 0.12065 -0.3048)
			(stroke
				(width 0.1)
				(type default)
			)
			(layer "F.Fab")
		)
		(fp_line
			(start 0.67945 -0.3048)
			(end 0.67945 0.3048)
			(stroke
				(width 0.1)
				(type default)
			)
			(layer "F.Fab")
		)
		(fp_line
			(start 0.67945 0.3048)
			(end 0.120396 0.3048)
			(stroke
				(width 0.1)
				(type default)
			)
			(layer "F.Fab")
		)
		(pad "1" smd circle
			(at -0.40005 0)
			(size 0 0)
			(layers "F.Cu" "F.Mask" "F.Paste")
			(net "P12V_OCP_V3_2_EN_R")
		)
		(pad "2" smd circle
			(at 0.40005 0)
			(size 0 0)
			(layers "F.Cu" "F.Mask" "F.Paste")
			(net "P12V_OCP_EN_2_R")
		)
	)
	(footprint ""
		(layer "F.Cu")
		(at 187.563506 -353.986084 90)
		(property "Reference" "PC506"
			(at 0 0 90)
			(layer "F.SilkS")
			(hide yes)
			(effects
				(font
					(size 1.27 1.27)
				)
			)
		)
		(property "Value" ""
			(at 0 0 90)
			(layer "F.Fab")
			(effects
				(font
					(size 1.27 1.27)
				)
			)
		)
		(duplicate_pad_numbers_are_jumpers no)
		(fp_line
			(start 0.7874 -0.4064)
			(end 0.7874 0.4064)
			(stroke
				(width 0.1524)
				(type default)
			)
			(layer "F.SilkS")
		)
		(fp_line
			(start -0.7874 -0.4064)
			(end 0.7874 -0.4064)
			(stroke
				(width 0.1524)
				(type default)
			)
			(layer "F.SilkS")
		)
		(fp_line
			(start 0.7874 0.4064)
			(end 0.445516 0.4064)
			(stroke
				(width 0.1524)
				(type default)
			)
			(layer "F.SilkS")
		)
		(fp_line
			(start -0.291084 0.4064)
			(end -0.7874 0.4064)
			(stroke
				(width 0.1524)
				(type default)
			)
			(layer "F.SilkS")
		)
		(fp_line
			(start -0.7874 0.4064)
			(end -0.7874 -0.4064)
			(stroke
				(width 0.1524)
				(type default)
			)
			(layer "F.SilkS")
		)
		(fp_line
			(start -0.12065 -0.305054)
			(end -0.12065 -0.2794)
			(stroke
				(width 0.1)
				(type default)
			)
			(layer "F.Fab")
		)
		(fp_line
			(start -0.67945 -0.305054)
			(end -0.12065 -0.305054)
			(stroke
				(width 0.1)
				(type default)
			)
			(layer "F.Fab")
		)
		(fp_line
			(start 0.67945 -0.3048)
			(end 0.67945 0.3048)
			(stroke
				(width 0.1)
				(type default)
			)
			(layer "F.Fab")
		)
		(fp_line
			(start 0.12065 -0.3048)
			(end 0.67945 -0.3048)
			(stroke
				(width 0.1)
				(type default)
			)
			(layer "F.Fab")
		)
		(fp_line
			(start 0.12065 -0.2794)
			(end 0.12065 -0.3048)
			(stroke
				(width 0.1)
				(type default)
			)
			(layer "F.Fab")
		)
		(fp_line
			(start -0.12065 -0.2794)
			(end 0.12065 -0.2794)
			(stroke
				(width 0.1)
				(type default)
			)
			(layer "F.Fab")
		)
		(fp_line
			(start 0.120396 0.2794)
			(end -0.12065 0.2794)
			(stroke
				(width 0.1)
				(type default)
			)
			(layer "F.Fab")
		)
		(fp_line
			(start -0.12065 0.2794)
			(end -0.12065 0.3048)
			(stroke
				(width 0.1)
				(type default)
			)
			(layer "F.Fab")
		)
		(fp_line
			(start 0.67945 0.3048)
			(end 0.120396 0.3048)
			(stroke
				(width 0.1)
				(type default)
			)
			(layer "F.Fab")
		)
		(fp_line
			(start 0.120396 0.3048)
			(end 0.120396 0.2794)
			(stroke
				(width 0.1)
				(type default)
			)
			(layer "F.Fab")
		)
		(fp_line
			(start -0.12065 0.3048)
			(end -0.67945 0.3048)
			(stroke
				(width 0.1)
				(type default)
			)
			(layer "F.Fab")
		)
		(fp_line
			(start -0.67945 0.3048)
			(end -0.67945 -0.305054)
			(stroke
				(width 0.1)
				(type default)
			)
			(layer "F.Fab")
		)
		(pad "1" smd circle
			(at -0.40005 0 90)
			(size 0 0)
			(layers "F.Cu" "F.Mask" "F.Paste")
			(net "PVDD11_S3_P1_VCC2")
		)
		(pad "2" smd circle
			(at 0.40005 0 90)
			(size 0 0)
			(layers "F.Cu" "F.Mask" "F.Paste")
			(net "GND")
		)
	)
)
